# T6G (Grand Teton) — schematic netlist excerpt (pin names and nets, part order shuffled) for the footprints in the layout excerpt that follows; sources: Cadence DE-HDL packaged netlist, KiCad conversion of 04192023_DAF0TMB3IC0_F0TG_MB_C_brd_V02_OCP.brd

R498  Q_RES  2.2K 5% CHIP  pkg 0402LF  page 34 : A = PVDD18_S5_P0 ; B = SMB_CPU0_4_SDA

PL47  Q_INDUCTOR4P_14  150NH IND  pkg L_TLM117513Q-151QL_11X7-5XA  page 222
  \1\  = SW_PVDDIO_P1_SW1
  \2\  = IND_PVDDIO_P1_CPL2
  \3\  = GND
  \4\  = PVDDIO_P1

(kicad_pcb
	(version 20260206)
	(generator "pcbnew")
	(generator_version "10.0")
	(general
		(thickness 1.6)
		(legacy_teardrops no)
	)
	(paper "A4")
	(title_block
		(title "04192023_DAF0TMB3IC0_F0TG_MB_C_brd_V02_OCP.brd")
		(comment 1 "Grand Teton / footprints 4109-4110 of 8354")
	)
	(layers
		(0 "F.Cu" signal "TOP")
		(4 "In1.Cu" signal "GND")
		(6 "In2.Cu" signal "IN1")
		(8 "In3.Cu" signal "GND1")
		(10 "In4.Cu" signal "IN2")
		(12 "In5.Cu" signal "GND2")
		(14 "In6.Cu" signal "IN3")
		(16 "In7.Cu" signal "GND3")
		(18 "In8.Cu" signal "VCC")
		(20 "In9.Cu" signal "VCC1")
		(22 "In10.Cu" signal "GND4")
		(24 "In11.Cu" signal "IN4")
		(26 "In12.Cu" signal "GND5")
		(28 "In13.Cu" signal "IN5")
		(30 "In14.Cu" signal "GND6")
		(32 "In15.Cu" signal "IN6")
		(34 "In16.Cu" signal "GND7")
		(2 "B.Cu" signal "BOTTOM")
		(9 "F.Adhes" user "F.Adhesive")
		(11 "B.Adhes" user "B.Adhesive")
		(13 "F.Paste" user "Package Geometry/Pastemask Top")
		(15 "B.Paste" user "Package Geometry/Pastemask Bottom")
		(5 "F.SilkS" user "Ref Des/Silkscreen Top")
		(7 "B.SilkS" user "Ref Des/Silkscreen Bottom")
		(1 "F.Mask" user "Board Geometry/Soldermask Top")
		(3 "B.Mask" user "Board Geometry/Soldermask Bottom")
		(17 "Dwgs.User" user "User.Drawings")
		(19 "Cmts.User" user "User.Comments")
		(21 "Eco1.User" user "User.Eco1")
		(23 "Eco2.User" user "User.Eco2")
		(25 "Edge.Cuts" user "Board Geometry/Outline")
		(27 "Margin" user)
		(31 "F.CrtYd" user "Package Geometry/Place Bound Top")
		(29 "B.CrtYd" user "Package Geometry/Place Bound Bottom")
		(35 "F.Fab" user "Ref Des/Assembly Top")
		(33 "B.Fab" user "Ref Des/Assembly Bottom")
	)
	(footprint ""
		(layer "F.Cu")
		(at 53.53431 -337.403948)
		(property "Reference" "PL47"
			(at -3.115056 -15.887446 0)
			(unlocked yes)
			(layer "F.SilkS")
			(effects
				(font
					(size 0.7874 0.5842)
					(thickness 0.1524)
				)
				(justify left)
			)
		)
		(property "Value" ""
			(at 0 0 0)
			(layer "F.Fab")
			(effects
				(font
					(size 1.27 1.27)
				)
			)
		)
		(duplicate_pad_numbers_are_jumpers no)
		(fp_line
			(start -3.750056 -5.500116)
			(end -2.393442 -5.500116)
			(stroke
				(width 0.1524)
				(type default)
			)
			(layer "F.SilkS")
		)
		(fp_line
			(start -3.750056 5.500116)
			(end -3.750056 -5.500116)
			(stroke
				(width 0.1524)
				(type default)
			)
			(layer "F.SilkS")
		)
		(fp_line
			(start -2.393442 5.500116)
			(end -3.750056 5.500116)
			(stroke
				(width 0.1524)
				(type default)
			)
			(layer "F.SilkS")
		)
		(fp_line
			(start 2.393442 5.500116)
			(end 3.750056 5.500116)
			(stroke
				(width 0.1524)
				(type default)
			)
			(layer "F.SilkS")
		)
		(fp_line
			(start 3.750056 -5.500116)
			(end 2.393442 -5.500116)
			(stroke
				(width 0.1524)
				(type default)
			)
			(layer "F.SilkS")
		)
		(fp_line
			(start 3.750056 5.500116)
			(end 3.750056 -5.500116)
			(stroke
				(width 0.1524)
				(type default)
			)
			(layer "F.SilkS")
		)
		(fp_poly
			(pts
				(xy -3.9116 -4.249928) (xy -4.3434 -4.034028) (xy -4.3434 -4.465828)
			)
			(stroke
				(width 0)
				(type default)
			)
			(fill yes)
			(layer "F.SilkS")
		)
		(fp_line
			(start -3.750056 -5.500116)
			(end -3.750056 5.500116)
			(stroke
				(width 0.1)
				(type default)
			)
			(layer "F.Fab")
		)
		(fp_line
			(start -3.750056 5.500116)
			(end 3.750056 5.500116)
			(stroke
				(width 0.1)
				(type default)
			)
			(layer "F.Fab")
		)
		(fp_line
			(start 3.750056 -5.500116)
			(end -3.750056 -5.500116)
			(stroke
				(width 0.1)
				(type default)
			)
			(layer "F.Fab")
		)
		(fp_line
			(start 3.750056 5.500116)
			(end 3.750056 -5.500116)
			(stroke
				(width 0.1)
				(type default)
			)
			(layer "F.Fab")
		)
		(fp_poly
			(pts
				(xy -4.9276 -4.757928) (xy -4.9276 -3.741928) (xy -3.9116 -4.249928)
			)
			(stroke
				(width 0)
				(type default)
			)
			(fill yes)
			(layer "F.Fab")
		)
		(pad "1" smd rect
			(at 0 -4.249928 270)
			(size 2.413 4.5212)
			(layers "F.Cu" "F.Mask" "F.Paste")
			(net "SW_PVDDIO_P1_SW1")
		)
		(pad "2" smd rect
			(at 0 -1.175004 270)
			(size 1.3716 4.5212)
			(layers "F.Cu" "F.Mask" "F.Paste")
			(net "IND_PVDDIO_P1_CPL2")
		)
		(pad "3" smd rect
			(at 0 1.175004 270)
			(size 1.3716 4.5212)
			(layers "F.Cu" "F.Mask" "F.Paste")
			(net "GND")
		)
		(pad "4" smd rect
			(at 0 4.249928 270)
			(size 2.413 4.5212)
			(layers "F.Cu" "F.Mask" "F.Paste")
			(net "PVDDIO_P1")
		)
	)
	(footprint ""
		(layer "F.Cu")
		(at 177.45583 -157.508194 -90)
		(property "Reference" "R498"
			(at 0 0 270)
			(layer "F.SilkS")
			(hide yes)
			(effects
				(font
					(size 1.27 1.27)
				)
			)
		)
		(property "Value" ""
			(at 0 0 270)
			(layer "F.Fab")
			(effects
				(font
					(size 1.27 1.27)
				)
			)
		)
		(duplicate_pad_numbers_are_jumpers no)
		(fp_line
			(start -0.7874 0.4064)
			(end -0.7874 -0.4064)
			(stroke
				(width 0.1524)
				(type default)
			)
			(layer "F.SilkS")
		)
		(fp_line
			(start 0.7874 0.4064)
			(end -0.7874 0.4064)
			(stroke
				(width 0.1524)
				(type default)
			)
			(layer "F.SilkS")
		)
		(fp_line
			(start -0.7874 -0.4064)
			(end 0.7874 -0.4064)
			(stroke
				(width 0.1524)
				(type default)
			)
			(layer "F.SilkS")
		)
		(fp_line
			(start 0.7874 -0.4064)
			(end 0.7874 0.4064)
			(stroke
				(width 0.1524)
				(type default)
			)
			(layer "F.SilkS")
		)
		(fp_line
			(start -0.67945 0.3048)
			(end -0.67945 -0.305054)
			(stroke
				(width 0.1)
				(type default)
			)
			(layer "F.Fab")
		)
		(fp_line
			(start -0.12065 0.3048)
			(end -0.67945 0.3048)
			(stroke
				(width 0.1)
				(type default)
			)
			(layer "F.Fab")
		)
		(fp_line
			(start 0.120396 0.3048)
			(end 0.120396 0.2794)
			(stroke
				(width 0.1)
				(type default)
			)
			(layer "F.Fab")
		)
		(fp_line
			(start 0.67945 0.3048)
			(end 0.120396 0.3048)
			(stroke
				(width 0.1)
				(type default)
			)
			(layer "F.Fab")
		)
		(fp_line
			(start -0.12065 0.2794)
			(end -0.12065 0.3048)
			(stroke
				(width 0.1)
				(type default)
			)
			(layer "F.Fab")
		)
		(fp_line
			(start 0.120396 0.2794)
			(end -0.12065 0.2794)
			(stroke
				(width 0.1)
				(type default)
			)
			(layer "F.Fab")
		)
		(fp_line
			(start -0.12065 -0.2794)
			(end 0.12065 -0.2794)
			(stroke
				(width 0.1)
				(type default)
			)
			(layer "F.Fab")
		)
		(fp_line
			(start 0.12065 -0.2794)
			(end 0.12065 -0.3048)
			(stroke
				(width 0.1)
				(type default)
			)
			(layer "F.Fab")
		)
		(fp_line
			(start 0.12065 -0.3048)
			(end 0.67945 -0.3048)
			(stroke
				(width 0.1)
				(type default)
			)
			(layer "F.Fab")
		)
		(fp_line
			(start 0.67945 -0.3048)
			(end 0.67945 0.3048)
			(stroke
				(width 0.1)
				(type default)
			)
			(layer "F.Fab")
		)
		(fp_line
			(start -0.67945 -0.305054)
			(end -0.12065 -0.305054)
			(stroke
				(width 0.1)
				(type default)
			)
			(layer "F.Fab")
		)
		(fp_line
			(start -0.12065 -0.305054)
			(end -0.12065 -0.2794)
			(stroke
				(width 0.1)
				(type default)
			)
			(layer "F.Fab")
		)
		(pad "1" smd circle
			(at -0.40005 0 270)
			(size 0 0)
			(layers "F.Cu" "F.Mask" "F.Paste")
			(net "PVDD18_S5_P0")
		)
		(pad "2" smd circle
			(at 0.40005 0 270)
			(size 0 0)
			(layers "F.Cu" "F.Mask" "F.Paste")
			(net "SMB_CPU0_4_SDA")
		)
	)
)
